FILE_TYPE = CONNECTIVITY;
{Allegro Design Entry HDL 16.6-p007 (v16-6-112F) 10/10/2012}
"PAGE_NUMBER" = 257;
0"NC";
END.
